(kicad_pcb
	(version 20260206)
	(generator "pcbnew")
	(generator_version "10.0")
	(general
		(thickness 1.6)
		(legacy_teardrops no)
	)
	(paper "A4")
	(title_block
		(title "v1-chassis-manager — T6M_CM_d_v01_1031_1645.brd")
		(comment 1 "Open CloudServer (Microsoft) / footprints 215-221 of 2512")
	)
	(layers
		(0 "F.Cu" signal "TOP")
		(4 "In1.Cu" signal "GND1")
		(6 "In2.Cu" signal "IN1")
		(8 "In3.Cu" signal "VCC1")
		(10 "In4.Cu" signal "VCC2")
		(12 "In5.Cu" signal "GND2")
		(14 "In6.Cu" signal "IN2")
		(16 "In7.Cu" signal "IN3")
		(18 "In8.Cu" signal "GND3")
		(2 "B.Cu" signal "BOTTOM")
		(9 "F.Adhes" user "F.Adhesive")
		(11 "B.Adhes" user "B.Adhesive")
		(13 "F.Paste" user "Package Geometry/Pastemask Top")
		(15 "B.Paste" user "Package Geometry/Pastemask Bottom")
		(5 "F.SilkS" user "Ref Des/Silkscreen Top")
		(7 "B.SilkS" user "Ref Des/Silkscreen Bottom")
		(1 "F.Mask" user "Board Geometry/Soldermask Top")
		(3 "B.Mask" user "Board Geometry/Soldermask Bottom")
		(17 "Dwgs.User" user "User.Drawings")
		(19 "Cmts.User" user "User.Comments")
		(21 "Eco1.User" user "User.Eco1")
		(23 "Eco2.User" user "User.Eco2")
		(25 "Edge.Cuts" user "Board Geometry/Outline")
		(27 "Margin" user)
		(31 "F.CrtYd" user "Package Geometry/Place Bound Top")
		(29 "B.CrtYd" user "Package Geometry/Place Bound Bottom")
		(35 "F.Fab" user "Ref Des/Assembly Top")
		(33 "B.Fab" user "Ref Des/Assembly Bottom")
	)
	(footprint ""
		(layer "F.Cu")
		(at 82.927952 -139.751562 180)
		(property "Reference" "U122"
			(at -3.44932 -0.056134 90)
			(unlocked yes)
			(layer "F.SilkS")
			(effects
				(font
					(size 0.7874 0.5842)
					(thickness 0.1524)
				)
				(justify left)
			)
		)
		(property "Value" ""
			(at 0 0 180)
			(layer "F.Fab")
			(effects
				(font
					(size 1.27 1.27)
				)
			)
		)
		(duplicate_pad_numbers_are_jumpers no)
		(fp_line
			(start 0.525018 3.075178)
			(end 0.525018 2.489962)
			(stroke
				(width 0.1524)
				(type default)
			)
			(layer "F.SilkS")
		)
		(fp_line
			(start 0.525018 3.075178)
			(end 0.525018 0.025146)
			(stroke
				(width 0.1524)
				(type default)
			)
			(layer "F.SilkS")
		)
		(fp_line
			(start 0.525018 0.686562)
			(end 0.525018 0.025146)
			(stroke
				(width 0.1524)
				(type default)
			)
			(layer "F.SilkS")
		)
		(fp_line
			(start 0.525018 0.025146)
			(end 0.320802 0.025146)
			(stroke
				(width 0.1524)
				(type default)
			)
			(layer "F.SilkS")
		)
		(fp_line
			(start 0.320802 3.075178)
			(end 0.525018 3.075178)
			(stroke
				(width 0.1524)
				(type default)
			)
			(layer "F.SilkS")
		)
		(fp_line
			(start -2.320798 0.025146)
			(end -2.525014 0.025146)
			(stroke
				(width 0.1524)
				(type default)
			)
			(layer "F.SilkS")
		)
		(fp_line
			(start -2.525014 3.075178)
			(end -2.320798 3.075178)
			(stroke
				(width 0.1524)
				(type default)
			)
			(layer "F.SilkS")
		)
		(fp_line
			(start -2.525014 3.075178)
			(end -2.525014 0.025146)
			(stroke
				(width 0.1524)
				(type default)
			)
			(layer "F.SilkS")
		)
		(fp_line
			(start -2.525014 2.540762)
			(end -2.525014 3.075178)
			(stroke
				(width 0.1524)
				(type default)
			)
			(layer "F.SilkS")
		)
		(fp_line
			(start -2.525014 0.025146)
			(end -2.525014 0.661162)
			(stroke
				(width 0.1524)
				(type default)
			)
			(layer "F.SilkS")
		)
		(fp_poly
			(pts
				(xy 0 -0.519938) (xy 0.299974 -1.420114) (xy -0.299974 -1.420114)
			)
			(stroke
				(width 0)
				(type default)
			)
			(fill yes)
			(layer "F.SilkS")
		)
		(fp_poly
			(pts
				(xy 0.525018 0.025146) (xy 0.244602 0.025146) (xy 0.244602 -0.532638) (xy -2.244598 -0.532638) (xy -2.244598 0.025146)
				(xy -2.525014 0.025146) (xy -2.525014 3.075178) (xy -2.244598 3.075178) (xy -2.244598 3.632962)
				(xy 0.244602 3.632962) (xy 0.244602 3.075178) (xy 0.525018 3.075178)
			)
			(stroke
				(width 0)
				(type default)
			)
			(fill no)
			(layer "F.CrtYd")
		)
		(fp_line
			(start 0.525018 3.075178)
			(end -2.525014 3.075178)
			(stroke
				(width 0.1)
				(type default)
			)
			(layer "F.Fab")
		)
		(fp_line
			(start 0.525018 0.025146)
			(end 0.525018 3.075178)
			(stroke
				(width 0.1)
				(type default)
			)
			(layer "F.Fab")
		)
		(fp_line
			(start -2.525014 3.075178)
			(end -2.525014 0.025146)
			(stroke
				(width 0.1)
				(type default)
			)
			(layer "F.Fab")
		)
		(fp_line
			(start -2.525014 0.025146)
			(end 0.525018 0.025146)
			(stroke
				(width 0.1)
				(type default)
			)
			(layer "F.Fab")
		)
		(fp_poly
			(pts
				(xy 0 -0.519938) (xy 0.302514 -1.427734) (xy -0.302514 -1.427734)
			)
			(stroke
				(width 0)
				(type default)
			)
			(fill yes)
			(layer "F.Fab")
		)
		(fp_text user "10"
			(at 0.729234 4.007612 0)
			(unlocked yes)
			(layer "F.SilkS")
			(effects
				(font
					(size 0.635 0.4064)
					(thickness 0.1524)
				)
				(justify left)
			)
		)
		(fp_text user "1"
			(at -0.482346 -0.944118 0)
			(unlocked yes)
			(layer "F.SilkS")
			(effects
				(font
					(size 0.635 0.4064)
					(thickness 0.1524)
				)
				(justify left)
			)
		)
		(fp_text user "5"
			(at -2.255774 -0.562102 0)
			(unlocked yes)
			(layer "F.SilkS")
			(effects
				(font
					(size 0.635 0.4064)
					(thickness 0.1524)
				)
				(justify left)
			)
		)
		(fp_text user "6"
			(at -2.274062 3.62077 0)
			(unlocked yes)
			(layer "F.SilkS")
			(effects
				(font
					(size 0.635 0.4064)
					(thickness 0.1524)
				)
				(justify left)
			)
		)
		(fp_text user "10"
			(at 1.565402 3.700272 0)
			(unlocked yes)
			(layer "F.Fab")
			(effects
				(font
					(size 0.7874 0.5842)
					(thickness 0.000001)
				)
				(justify left)
			)
		)
		(fp_text user "1"
			(at 0.790702 -0.695706 0)
			(unlocked yes)
			(layer "F.Fab")
			(effects
				(font
					(size 0.7874 0.5842)
					(thickness 0.000001)
				)
				(justify left)
			)
		)
		(fp_text user "6"
			(at -2.155698 3.725672 0)
			(unlocked yes)
			(layer "F.Fab")
			(effects
				(font
					(size 0.7874 0.5842)
					(thickness 0.000001)
				)
				(justify left)
			)
		)
		(fp_text user "5"
			(at -2.155698 -0.695706 0)
			(unlocked yes)
			(layer "F.Fab")
			(effects
				(font
					(size 0.7874 0.5842)
					(thickness 0.000001)
				)
				(justify left)
			)
		)
		(pad "1" smd rect
			(at 0 0)
			(size 0.2794 0.9144)
			(layers "F.Cu" "F.Mask" "F.Paste")
			(net "P1V26_BMC_NODE1")
		)
		(pad "2" smd rect
			(at -0.499872 0)
			(size 0.2794 0.9144)
			(layers "F.Cu" "F.Mask" "F.Paste")
			(net "P1V26_BMC_NODE1")
		)
		(pad "3" smd rect
			(at -0.999998 0)
			(size 0.2794 0.9144)
			(layers "F.Cu" "F.Mask" "F.Paste")
			(net "P1V26_BMC_NODE1")
		)
		(pad "4" smd rect
			(at -1.500124 0)
			(size 0.2794 0.9144)
			(layers "F.Cu" "F.Mask" "F.Paste")
			(net "P1V26_BMC_NODE1_ADJ")
		)
		(pad "5" smd rect
			(at -1.999996 0 180)
			(size 0.2794 0.9144)
			(layers "F.Cu" "F.Mask" "F.Paste")
			(net "PWRGD_NODE1_P1V26_BMC_PG")
		)
		(pad "6" smd rect
			(at -1.999996 3.100324 180)
			(size 0.2794 0.9144)
			(layers "F.Cu" "F.Mask" "F.Paste")
			(net "FM_CPLD_NODE1_P1V26_BMC_EN")
		)
		(pad "7" smd rect
			(at -1.500124 3.100324)
			(size 0.2794 0.9144)
			(layers "F.Cu" "F.Mask" "F.Paste")
			(net "P1V8_NODE1")
		)
		(pad "8" smd rect
			(at -0.999998 3.100324)
			(size 0.2794 0.9144)
			(layers "F.Cu" "F.Mask" "F.Paste")
			(net "P1V8_NODE1")
		)
		(pad "9" smd rect
			(at -0.499872 3.100324)
			(size 0.2794 0.9144)
			(layers "F.Cu" "F.Mask" "F.Paste")
			(net "P1V8_NODE1")
		)
		(pad "10" smd rect
			(at 0 3.100324)
			(size 0.2794 0.9144)
			(layers "F.Cu" "F.Mask" "F.Paste")
			(net "P5V_STB_NODE1")
		)
		(pad "TH" smd rect
			(at -0.999998 1.550162 90)
			(size 1.7526 2.667)
			(layers "F.Cu" "F.Mask" "F.Paste")
			(net "GND")
		)
		(zone
			(layer "F.Cu")
			(hatch none 0.5)
			(connect_pads
				(clearance 0)
			)
			(min_thickness 0.25)
			(keepout
				(tracks allowed)
				(vias not_allowed)
				(pads allowed)
				(copperpour not_allowed)
				(footprints allowed)
			)
			(placement
				(enabled no)
				(sheetname "")
			)
			(fill
				(thermal_gap 0.5)
				(thermal_bridge_width 0.5)
				(island_removal_mode 0)
			)
			(polygon
				(pts
					(xy 82.394552 -140.284962) (xy 85.442552 -140.284962) (xy 85.442552 -142.316962) (xy 82.394552 -142.316962)
					(xy 82.394552 -140.386562) (xy 82.521552 -140.386562) (xy 82.521552 -142.240762) (xy 85.340952 -142.240762)
					(xy 85.340952 -140.361162) (xy 82.394552 -140.361162)
				)
			)
		)
	)
	(footprint ""
		(layer "F.Cu")
		(at 42.252646 -112.033558 180)
		(property "Reference" "PC21"
			(at 1.472692 4.605782 0)
			(unlocked yes)
			(layer "F.SilkS")
			(effects
				(font
					(size 0.7874 0.5842)
					(thickness 0.1524)
				)
				(justify left)
			)
		)
		(property "Value" ""
			(at 0 0 180)
			(layer "F.Fab")
			(effects
				(font
					(size 1.27 1.27)
				)
			)
		)
		(duplicate_pad_numbers_are_jumpers no)
		(fp_line
			(start 0.7874 0.4064)
			(end -0.7874 0.4064)
			(stroke
				(width 0.1524)
				(type default)
			)
			(layer "F.SilkS")
		)
		(fp_line
			(start 0.7874 -0.4064)
			(end 0.7874 0.4064)
			(stroke
				(width 0.1524)
				(type default)
			)
			(layer "F.SilkS")
		)
		(fp_line
			(start 0 0.381)
			(end 0 -0.381)
			(stroke
				(width 0.1524)
				(type default)
			)
			(layer "F.SilkS")
		)
		(fp_line
			(start -0.7874 0.4064)
			(end -0.7874 -0.4064)
			(stroke
				(width 0.1524)
				(type default)
			)
			(layer "F.SilkS")
		)
		(fp_line
			(start -0.7874 -0.4064)
			(end 0.7874 -0.4064)
			(stroke
				(width 0.1524)
				(type default)
			)
			(layer "F.SilkS")
		)
		(fp_poly
			(pts
				(xy -0.5334 0.254) (xy -0.635 0.254) (xy -0.635 0.2286) (xy -0.635 -0.254) (xy -0.5334 -0.254) (xy -0.5334 -0.2794)
				(xy 0.5334 -0.2794) (xy 0.5334 -0.254) (xy 0.635 -0.254) (xy 0.635 0.254) (xy 0.5334 0.254) (xy 0.5334 0.2794)
				(xy -0.508 0.2794) (xy -0.5334 0.2794)
			)
			(stroke
				(width 0)
				(type default)
			)
			(fill no)
			(layer "F.CrtYd")
		)
		(pad "1" smd rect
			(at 0.40005 0 180)
			(size 0.4572 0.508)
			(layers "F.Cu" "F.Mask" "F.Paste")
			(net "P3V3_STB_NODE1_FB")
		)
		(pad "2" smd rect
			(at -0.40005 0 180)
			(size 0.4572 0.508)
			(layers "F.Cu" "F.Mask" "F.Paste")
			(net "P3V3_STB_NODE1")
		)
	)
	(footprint ""
		(layer "F.Cu")
		(at 129.74447 -112.04575)
		(property "Reference" "R4"
			(at -2.464054 0.117602 0)
			(unlocked yes)
			(layer "F.SilkS")
			(effects
				(font
					(size 0.7874 0.5842)
					(thickness 0.1524)
				)
				(justify left)
			)
		)
		(property "Value" ""
			(at 0 0 0)
			(layer "F.Fab")
			(effects
				(font
					(size 1.27 1.27)
				)
			)
		)
		(duplicate_pad_numbers_are_jumpers no)
		(fp_line
			(start -0.7874 -0.4064)
			(end 0.7874 -0.4064)
			(stroke
				(width 0.1524)
				(type default)
			)
			(layer "F.SilkS")
		)
		(fp_line
			(start -0.7874 0.4064)
			(end -0.7874 -0.4064)
			(stroke
				(width 0.1524)
				(type default)
			)
			(layer "F.SilkS")
		)
		(fp_line
			(start 0.7874 -0.4064)
			(end 0.7874 0.4064)
			(stroke
				(width 0.1524)
				(type default)
			)
			(layer "F.SilkS")
		)
		(fp_line
			(start 0.7874 0.4064)
			(end -0.7874 0.4064)
			(stroke
				(width 0.1524)
				(type default)
			)
			(layer "F.SilkS")
		)
		(fp_poly
			(pts
				(xy -0.508 0.2794) (xy -0.508 0.2286) (xy -0.635 0.2286) (xy -0.635 -0.254) (xy -0.5334 -0.254)
				(xy -0.5334 -0.2794) (xy 0.5334 -0.2794) (xy 0.5334 -0.254) (xy 0.635 -0.254) (xy 0.635 0.254) (xy 0.5334 0.254)
				(xy 0.5334 0.2794)
			)
			(stroke
				(width 0)
				(type default)
			)
			(fill no)
			(layer "F.CrtYd")
		)
		(pad "1" smd rect
			(at 0.40005 0)
			(size 0.4572 0.508)
			(layers "F.Cu" "F.Mask" "F.Paste")
			(net "XTAL_CLK_NODE1_X1")
		)
		(pad "2" smd rect
			(at -0.40005 0)
			(size 0.4572 0.508)
			(layers "F.Cu" "F.Mask" "F.Paste")
			(net "XTAL_CLK_NODE1_X2")
		)
	)
	(footprint ""
		(layer "F.Cu")
		(at 176.90465 -56.227472 180)
		(property "Reference" "C561"
			(at 3.75666 2.155698 0)
			(unlocked yes)
			(layer "F.SilkS")
			(effects
				(font
					(size 0.7874 0.5842)
					(thickness 0.1524)
				)
				(justify left)
			)
		)
		(property "Value" ""
			(at 0 0 180)
			(layer "F.Fab")
			(effects
				(font
					(size 1.27 1.27)
				)
			)
		)
		(duplicate_pad_numbers_are_jumpers no)
		(fp_line
			(start 0.7874 0.4064)
			(end -0.7874 0.4064)
			(stroke
				(width 0.1524)
				(type default)
			)
			(layer "F.SilkS")
		)
		(fp_line
			(start 0.7874 -0.4064)
			(end 0.7874 0.4064)
			(stroke
				(width 0.1524)
				(type default)
			)
			(layer "F.SilkS")
		)
		(fp_line
			(start 0 0.381)
			(end 0 -0.381)
			(stroke
				(width 0.1524)
				(type default)
			)
			(layer "F.SilkS")
		)
		(fp_line
			(start -0.7874 0.4064)
			(end -0.7874 -0.4064)
			(stroke
				(width 0.1524)
				(type default)
			)
			(layer "F.SilkS")
		)
		(fp_line
			(start -0.7874 -0.4064)
			(end 0.7874 -0.4064)
			(stroke
				(width 0.1524)
				(type default)
			)
			(layer "F.SilkS")
		)
		(fp_poly
			(pts
				(xy -0.5334 0.254) (xy -0.635 0.254) (xy -0.635 0.2286) (xy -0.635 -0.254) (xy -0.5334 -0.254) (xy -0.5334 -0.2794)
				(xy 0.5334 -0.2794) (xy 0.5334 -0.254) (xy 0.635 -0.254) (xy 0.635 0.254) (xy 0.5334 0.254) (xy 0.5334 0.2794)
				(xy -0.508 0.2794) (xy -0.5334 0.2794)
			)
			(stroke
				(width 0)
				(type default)
			)
			(fill no)
			(layer "F.CrtYd")
		)
		(pad "1" smd rect
			(at 0.40005 0 180)
			(size 0.4572 0.508)
			(layers "F.Cu" "F.Mask" "F.Paste")
			(net "USBPWR_P1")
		)
		(pad "2" smd rect
			(at -0.40005 0 180)
			(size 0.4572 0.508)
			(layers "F.Cu" "F.Mask" "F.Paste")
			(net "GND")
		)
	)
	(footprint ""
		(layer "F.Cu")
		(at 149.508972 -32.570928 180)
		(property "Reference" "R649"
			(at 1.179576 3.705352 0)
			(unlocked yes)
			(layer "F.SilkS")
			(effects
				(font
					(size 0.7874 0.5842)
					(thickness 0.1524)
				)
				(justify left)
			)
		)
		(property "Value" ""
			(at 0 0 180)
			(layer "F.Fab")
			(effects
				(font
					(size 1.27 1.27)
				)
			)
		)
		(duplicate_pad_numbers_are_jumpers no)
		(fp_line
			(start 0.7874 0.4064)
			(end -0.7874 0.4064)
			(stroke
				(width 0.1524)
				(type default)
			)
			(layer "F.SilkS")
		)
		(fp_line
			(start 0.7874 -0.4064)
			(end 0.7874 0.4064)
			(stroke
				(width 0.1524)
				(type default)
			)
			(layer "F.SilkS")
		)
		(fp_line
			(start -0.7874 0.4064)
			(end -0.7874 -0.4064)
			(stroke
				(width 0.1524)
				(type default)
			)
			(layer "F.SilkS")
		)
		(fp_line
			(start -0.7874 -0.4064)
			(end 0.7874 -0.4064)
			(stroke
				(width 0.1524)
				(type default)
			)
			(layer "F.SilkS")
		)
		(fp_poly
			(pts
				(xy -0.508 0.2794) (xy -0.508 0.2286) (xy -0.635 0.2286) (xy -0.635 -0.254) (xy -0.5334 -0.254)
				(xy -0.5334 -0.2794) (xy 0.5334 -0.2794) (xy 0.5334 -0.254) (xy 0.635 -0.254) (xy 0.635 0.254) (xy 0.5334 0.254)
				(xy 0.5334 0.2794)
			)
			(stroke
				(width 0)
				(type default)
			)
			(fill no)
			(layer "F.CrtYd")
		)
		(pad "1" smd rect
			(at 0.40005 0 180)
			(size 0.4572 0.508)
			(layers "F.Cu" "F.Mask" "F.Paste")
			(net "P3V3_NODE1")
		)
		(pad "2" smd rect
			(at -0.40005 0 180)
			(size 0.4572 0.508)
			(layers "F.Cu" "F.Mask" "F.Paste")
			(net "N21624804")
		)
	)
	(footprint ""
		(layer "F.Cu")
		(at 55.10276 -185.205624 -90)
		(property "Reference" "R820"
			(at -4.006088 0.048514 90)
			(unlocked yes)
			(layer "F.SilkS")
			(effects
				(font
					(size 0.7874 0.5842)
					(thickness 0.1524)
				)
				(justify left)
			)
		)
		(property "Value" ""
			(at 0 0 270)
			(layer "F.Fab")
			(effects
				(font
					(size 1.27 1.27)
				)
			)
		)
		(duplicate_pad_numbers_are_jumpers no)
		(fp_line
			(start -0.7874 0.4064)
			(end -0.7874 -0.4064)
			(stroke
				(width 0.1524)
				(type default)
			)
			(layer "F.SilkS")
		)
		(fp_line
			(start 0.7874 0.4064)
			(end -0.7874 0.4064)
			(stroke
				(width 0.1524)
				(type default)
			)
			(layer "F.SilkS")
		)
		(fp_line
			(start -0.7874 -0.4064)
			(end 0.7874 -0.4064)
			(stroke
				(width 0.1524)
				(type default)
			)
			(layer "F.SilkS")
		)
		(fp_line
			(start 0.7874 -0.4064)
			(end 0.7874 0.4064)
			(stroke
				(width 0.1524)
				(type default)
			)
			(layer "F.SilkS")
		)
		(fp_poly
			(pts
				(xy -0.508 0.2794) (xy -0.508 0.2286) (xy -0.635 0.2286) (xy -0.635 -0.254) (xy -0.5334 -0.254)
				(xy -0.5334 -0.2794) (xy 0.5334 -0.2794) (xy 0.5334 -0.254) (xy 0.635 -0.254) (xy 0.635 0.254) (xy 0.5334 0.254)
				(xy 0.5334 0.2794)
			)
			(stroke
				(width 0)
				(type default)
			)
			(fill no)
			(layer "F.CrtYd")
		)
		(pad "1" smd rect
			(at 0.40005 0 270)
			(size 0.4572 0.508)
			(layers "F.Cu" "F.Mask" "F.Paste")
			(net "I2C_PSU1_SCL")
		)
		(pad "2" smd rect
			(at -0.40005 0 270)
			(size 0.4572 0.508)
			(layers "F.Cu" "F.Mask" "F.Paste")
			(net "I2C_PSU1_R_SCL")
		)
	)
	(footprint ""
		(layer "F.Cu")
		(at 36.354004 -75.37069 180)
		(property "Reference" "L9"
			(at 5.272786 0.501396 0)
			(unlocked yes)
			(layer "F.SilkS")
			(effects
				(font
					(size 0.7874 0.5842)
					(thickness 0.1524)
				)
				(justify left)
			)
		)
		(property "Value" ""
			(at 0 0 180)
			(layer "F.Fab")
			(effects
				(font
					(size 1.27 1.27)
				)
			)
		)
		(duplicate_pad_numbers_are_jumpers no)
		(fp_line
			(start 0.7874 0.4064)
			(end -0.7874 0.4064)
			(stroke
				(width 0.1524)
				(type default)
			)
			(layer "F.SilkS")
		)
		(fp_line
			(start 0.7874 -0.4064)
			(end 0.7874 0.4064)
			(stroke
				(width 0.1524)
				(type default)
			)
			(layer "F.SilkS")
		)
		(fp_line
			(start 0.0889 0.4064)
			(end 0.0889 -0.4064)
			(stroke
				(width 0.1524)
				(type default)
			)
			(layer "F.SilkS")
		)
		(fp_line
			(start -0.0889 0.4064)
			(end -0.0889 -0.4064)
			(stroke
				(width 0.1524)
				(type default)
			)
			(layer "F.SilkS")
		)
		(fp_line
			(start -0.7874 0.4064)
			(end -0.7874 -0.4064)
			(stroke
				(width 0.1524)
				(type default)
			)
			(layer "F.SilkS")
		)
		(fp_line
			(start -0.7874 -0.4064)
			(end 0.7874 -0.4064)
			(stroke
				(width 0.1524)
				(type default)
			)
			(layer "F.SilkS")
		)
		(fp_poly
			(pts
				(xy -0.5334 0.254) (xy -0.635 0.254) (xy -0.635 0.2286) (xy -0.635 -0.254) (xy -0.5334 -0.254) (xy -0.5334 -0.2794)
				(xy 0.5334 -0.2794) (xy 0.5334 -0.254) (xy 0.635 -0.254) (xy 0.635 0.254) (xy 0.5334 0.254) (xy 0.5334 0.2794)
				(xy -0.508 0.2794) (xy -0.5334 0.2794)
			)
			(stroke
				(width 0)
				(type default)
			)
			(fill no)
			(layer "F.CrtYd")
		)
		(pad "1" smd rect
			(at 0.40005 0 180)
			(size 0.4572 0.508)
			(layers "F.Cu" "F.Mask" "F.Paste")
			(net "P1V8_NODE1")
		)
		(pad "2" smd rect
			(at -0.40005 0 180)
			(size 0.4572 0.508)
			(layers "F.Cu" "F.Mask" "F.Paste")
			(net "P1V8_VCCASFRHPLL_NODE1")
		)
	)
)
